(kicad_pcb
	(version 20260206)
	(generator "pcbnew")
	(generator_version "10.0")
	(general
		(thickness 1.6)
		(legacy_teardrops no)
	)
	(paper "A4")
	(title_block
		(title "01162023_DA0F0TEBIF0_F0T_Expander_BD_F_brd_V02_OCP.brd")
		(comment 1 "Grand Teton / footprints 9641-9649 of 9728")
	)
	(layers
		(0 "F.Cu" signal "TOP")
		(4 "In1.Cu" signal "GND")
		(6 "In2.Cu" signal "VCC")
		(8 "In3.Cu" signal "VCC1")
		(10 "In4.Cu" signal "GND1")
		(12 "In5.Cu" signal "IN1")
		(14 "In6.Cu" signal "GND2")
		(16 "In7.Cu" signal "IN2")
		(18 "In8.Cu" signal "GND3")
		(20 "In9.Cu" signal "IN3")
		(22 "In10.Cu" signal "GND4")
		(24 "In11.Cu" signal "IN4")
		(26 "In12.Cu" signal "GND5")
		(28 "In13.Cu" signal "IN5")
		(30 "In14.Cu" signal "GND6")
		(32 "In15.Cu" signal "IN6")
		(34 "In16.Cu" signal "GND7")
		(2 "B.Cu" signal "BOTTOM")
		(9 "F.Adhes" user "F.Adhesive")
		(11 "B.Adhes" user "B.Adhesive")
		(13 "F.Paste" user "Package Geometry/Pastemask Top")
		(15 "B.Paste" user "Package Geometry/Pastemask Bottom")
		(5 "F.SilkS" user "Ref Des/Silkscreen Top")
		(7 "B.SilkS" user "Ref Des/Silkscreen Bottom")
		(1 "F.Mask" user "Board Geometry/Soldermask Top")
		(3 "B.Mask" user "Board Geometry/Soldermask Bottom")
		(17 "Dwgs.User" user "User.Drawings")
		(19 "Cmts.User" user "User.Comments")
		(21 "Eco1.User" user "User.Eco1")
		(23 "Eco2.User" user "User.Eco2")
		(25 "Edge.Cuts" user "Board Geometry/Outline")
		(27 "Margin" user)
		(31 "F.CrtYd" user "Package Geometry/Place Bound Top")
		(29 "B.CrtYd" user "Package Geometry/Place Bound Bottom")
		(35 "F.Fab" user "Ref Des/Assembly Top")
		(33 "B.Fab" user "Ref Des/Assembly Bottom")
	)
	(footprint ""
		(layer "B.Cu")
		(at 282.364942 -301.599854 -90)
		(property "Reference" "C1681"
			(at 0 0 90)
			(layer "B.SilkS")
			(hide yes)
			(effects
				(font
					(size 1.27 1.27)
				)
				(justify mirror)
			)
		)
		(property "Value" ""
			(at 0 0 90)
			(layer "B.Fab")
			(effects
				(font
					(size 1.27 1.27)
				)
				(justify mirror)
			)
		)
		(duplicate_pad_numbers_are_jumpers no)
		(fp_line
			(start -0.299974 0.150114)
			(end 0.299974 0.150114)
			(stroke
				(width 0.1)
				(type default)
			)
			(layer "B.Fab")
		)
		(fp_line
			(start 0.299974 0.150114)
			(end 0.299974 -0.150114)
			(stroke
				(width 0.1)
				(type default)
			)
			(layer "B.Fab")
		)
		(fp_line
			(start -0.299974 -0.150114)
			(end -0.299974 0.150114)
			(stroke
				(width 0.1)
				(type default)
			)
			(layer "B.Fab")
		)
		(fp_line
			(start 0.299974 -0.150114)
			(end -0.299974 -0.150114)
			(stroke
				(width 0.1)
				(type default)
			)
			(layer "B.Fab")
		)
		(pad "1" smd rect
			(at 0.2667 0 90)
			(size 0.3048 0.381)
			(layers "B.Cu" "B.Mask" "B.Paste")
			(net "P0V8_SERDES_VDDA_PEX2")
		)
		(pad "2" smd rect
			(at -0.2667 0 90)
			(size 0.3048 0.381)
			(layers "B.Cu" "B.Mask" "B.Paste")
			(net "GND")
		)
	)
	(footprint ""
		(layer "B.Cu")
		(at 210.81873 -234.080304 -90)
		(property "Reference" "R6330"
			(at 0 0 90)
			(layer "B.SilkS")
			(hide yes)
			(effects
				(font
					(size 1.27 1.27)
				)
				(justify mirror)
			)
		)
		(property "Value" ""
			(at 0 0 90)
			(layer "B.Fab")
			(effects
				(font
					(size 1.27 1.27)
				)
				(justify mirror)
			)
		)
		(duplicate_pad_numbers_are_jumpers no)
		(fp_line
			(start -0.7874 0.4064)
			(end 0.7874 0.4064)
			(stroke
				(width 0.1524)
				(type default)
			)
			(layer "B.SilkS")
		)
		(fp_line
			(start 0.7874 0.4064)
			(end 0.7874 -0.4064)
			(stroke
				(width 0.1524)
				(type default)
			)
			(layer "B.SilkS")
		)
		(fp_line
			(start -0.7874 -0.4064)
			(end -0.7874 0.4064)
			(stroke
				(width 0.1524)
				(type default)
			)
			(layer "B.SilkS")
		)
		(fp_line
			(start 0.7874 -0.4064)
			(end -0.7874 -0.4064)
			(stroke
				(width 0.1524)
				(type default)
			)
			(layer "B.SilkS")
		)
		(fp_line
			(start -0.67945 0.3048)
			(end -0.120396 0.3048)
			(stroke
				(width 0.1)
				(type default)
			)
			(layer "B.Fab")
		)
		(fp_line
			(start -0.120396 0.3048)
			(end -0.120396 0.2794)
			(stroke
				(width 0.1)
				(type default)
			)
			(layer "B.Fab")
		)
		(fp_line
			(start 0.12065 0.3048)
			(end 0.67945 0.3048)
			(stroke
				(width 0.1)
				(type default)
			)
			(layer "B.Fab")
		)
		(fp_line
			(start 0.67945 0.3048)
			(end 0.67945 -0.305054)
			(stroke
				(width 0.1)
				(type default)
			)
			(layer "B.Fab")
		)
		(fp_line
			(start -0.120396 0.2794)
			(end 0.12065 0.2794)
			(stroke
				(width 0.1)
				(type default)
			)
			(layer "B.Fab")
		)
		(fp_line
			(start 0.12065 0.2794)
			(end 0.12065 0.3048)
			(stroke
				(width 0.1)
				(type default)
			)
			(layer "B.Fab")
		)
		(fp_line
			(start -0.12065 -0.2794)
			(end -0.12065 -0.3048)
			(stroke
				(width 0.1)
				(type default)
			)
			(layer "B.Fab")
		)
		(fp_line
			(start 0.12065 -0.2794)
			(end -0.12065 -0.2794)
			(stroke
				(width 0.1)
				(type default)
			)
			(layer "B.Fab")
		)
		(fp_line
			(start -0.67945 -0.3048)
			(end -0.67945 0.3048)
			(stroke
				(width 0.1)
				(type default)
			)
			(layer "B.Fab")
		)
		(fp_line
			(start -0.12065 -0.3048)
			(end -0.67945 -0.3048)
			(stroke
				(width 0.1)
				(type default)
			)
			(layer "B.Fab")
		)
		(fp_line
			(start 0.12065 -0.305054)
			(end 0.12065 -0.2794)
			(stroke
				(width 0.1)
				(type default)
			)
			(layer "B.Fab")
		)
		(fp_line
			(start 0.67945 -0.305054)
			(end 0.12065 -0.305054)
			(stroke
				(width 0.1)
				(type default)
			)
			(layer "B.Fab")
		)
		(pad "1" smd circle
			(at 0.40005 0 90)
			(size 0 0)
			(layers "B.Cu" "B.Mask" "B.Paste")
			(net "SMB_PEX2_SCL")
		)
		(pad "2" smd circle
			(at -0.40005 0 90)
			(size 0 0)
			(layers "B.Cu" "B.Mask" "B.Paste")
			(net "SMB_PEX2_MUX_SCL")
		)
	)
	(footprint ""
		(layer "B.Cu")
		(at 182.39994 -290.199826 90)
		(property "Reference" "C1438"
			(at 0 0 90)
			(layer "B.SilkS")
			(hide yes)
			(effects
				(font
					(size 1.27 1.27)
				)
				(justify mirror)
			)
		)
		(property "Value" ""
			(at 0 0 90)
			(layer "B.Fab")
			(effects
				(font
					(size 1.27 1.27)
				)
				(justify mirror)
			)
		)
		(duplicate_pad_numbers_are_jumpers no)
		(fp_line
			(start 0.299974 -0.150114)
			(end -0.299974 -0.150114)
			(stroke
				(width 0.1)
				(type default)
			)
			(layer "B.Fab")
		)
		(fp_line
			(start -0.299974 -0.150114)
			(end -0.299974 0.150114)
			(stroke
				(width 0.1)
				(type default)
			)
			(layer "B.Fab")
		)
		(fp_line
			(start 0.299974 0.150114)
			(end 0.299974 -0.150114)
			(stroke
				(width 0.1)
				(type default)
			)
			(layer "B.Fab")
		)
		(fp_line
			(start -0.299974 0.150114)
			(end 0.299974 0.150114)
			(stroke
				(width 0.1)
				(type default)
			)
			(layer "B.Fab")
		)
		(pad "1" smd rect
			(at 0.2667 0 270)
			(size 0.3048 0.381)
			(layers "B.Cu" "B.Mask" "B.Paste")
			(net "P0V8_SERDES_VDDA_PEX1")
		)
		(pad "2" smd rect
			(at -0.2667 0 270)
			(size 0.3048 0.381)
			(layers "B.Cu" "B.Mask" "B.Paste")
			(net "GND")
		)
	)
	(footprint ""
		(layer "B.Cu")
		(at 402.724874 -286.399732 90)
		(property "Reference" "C3501"
			(at 0 0 90)
			(layer "B.SilkS")
			(hide yes)
			(effects
				(font
					(size 1.27 1.27)
				)
				(justify mirror)
			)
		)
		(property "Value" ""
			(at 0 0 90)
			(layer "B.Fab")
			(effects
				(font
					(size 1.27 1.27)
				)
				(justify mirror)
			)
		)
		(duplicate_pad_numbers_are_jumpers no)
		(fp_line
			(start 0.299974 -0.150114)
			(end -0.299974 -0.150114)
			(stroke
				(width 0.1)
				(type default)
			)
			(layer "B.Fab")
		)
		(fp_line
			(start -0.299974 -0.150114)
			(end -0.299974 0.150114)
			(stroke
				(width 0.1)
				(type default)
			)
			(layer "B.Fab")
		)
		(fp_line
			(start 0.299974 0.150114)
			(end 0.299974 -0.150114)
			(stroke
				(width 0.1)
				(type default)
			)
			(layer "B.Fab")
		)
		(fp_line
			(start -0.299974 0.150114)
			(end 0.299974 0.150114)
			(stroke
				(width 0.1)
				(type default)
			)
			(layer "B.Fab")
		)
		(pad "1" smd rect
			(at 0.2667 0 270)
			(size 0.3048 0.381)
			(layers "B.Cu" "B.Mask" "B.Paste")
			(net "P1V25_SERDES_VDDPLL_PEX3")
		)
		(pad "2" smd rect
			(at -0.2667 0 270)
			(size 0.3048 0.381)
			(layers "B.Cu" "B.Mask" "B.Paste")
			(net "GND")
		)
	)
	(footprint ""
		(layer "B.Cu")
		(at 164.824918 -297.79976 -90)
		(property "Reference" "C1367"
			(at 0 0 90)
			(layer "B.SilkS")
			(hide yes)
			(effects
				(font
					(size 1.27 1.27)
				)
				(justify mirror)
			)
		)
		(property "Value" ""
			(at 0 0 90)
			(layer "B.Fab")
			(effects
				(font
					(size 1.27 1.27)
				)
				(justify mirror)
			)
		)
		(duplicate_pad_numbers_are_jumpers no)
		(fp_line
			(start -0.299974 0.150114)
			(end 0.299974 0.150114)
			(stroke
				(width 0.1)
				(type default)
			)
			(layer "B.Fab")
		)
		(fp_line
			(start 0.299974 0.150114)
			(end 0.299974 -0.150114)
			(stroke
				(width 0.1)
				(type default)
			)
			(layer "B.Fab")
		)
		(fp_line
			(start -0.299974 -0.150114)
			(end -0.299974 0.150114)
			(stroke
				(width 0.1)
				(type default)
			)
			(layer "B.Fab")
		)
		(fp_line
			(start 0.299974 -0.150114)
			(end -0.299974 -0.150114)
			(stroke
				(width 0.1)
				(type default)
			)
			(layer "B.Fab")
		)
		(pad "1" smd rect
			(at 0.2667 0 90)
			(size 0.3048 0.381)
			(layers "B.Cu" "B.Mask" "B.Paste")
			(net "P0V8_PEX1")
		)
		(pad "2" smd rect
			(at -0.2667 0 90)
			(size 0.3048 0.381)
			(layers "B.Cu" "B.Mask" "B.Paste")
			(net "GND")
		)
	)
	(footprint ""
		(layer "B.Cu")
		(at 233.412792 -90.50528 -90)
		(property "Reference" "C2619"
			(at 0 0 90)
			(layer "B.SilkS")
			(hide yes)
			(effects
				(font
					(size 1.27 1.27)
				)
				(justify mirror)
			)
		)
		(property "Value" ""
			(at 0 0 90)
			(layer "B.Fab")
			(effects
				(font
					(size 1.27 1.27)
				)
				(justify mirror)
			)
		)
		(duplicate_pad_numbers_are_jumpers no)
		(fp_line
			(start -0.7874 0.4064)
			(end 0.7874 0.4064)
			(stroke
				(width 0.1524)
				(type default)
			)
			(layer "B.SilkS")
		)
		(fp_line
			(start 0.7874 0.4064)
			(end 0.7874 -0.4064)
			(stroke
				(width 0.1524)
				(type default)
			)
			(layer "B.SilkS")
		)
		(fp_line
			(start -0.7874 -0.4064)
			(end -0.7874 0.4064)
			(stroke
				(width 0.1524)
				(type default)
			)
			(layer "B.SilkS")
		)
		(fp_line
			(start 0.7874 -0.4064)
			(end -0.7874 -0.4064)
			(stroke
				(width 0.1524)
				(type default)
			)
			(layer "B.SilkS")
		)
		(fp_line
			(start -0.67945 0.3048)
			(end -0.120396 0.3048)
			(stroke
				(width 0.1)
				(type default)
			)
			(layer "B.Fab")
		)
		(fp_line
			(start -0.120396 0.3048)
			(end -0.120396 0.2794)
			(stroke
				(width 0.1)
				(type default)
			)
			(layer "B.Fab")
		)
		(fp_line
			(start 0.12065 0.3048)
			(end 0.67945 0.3048)
			(stroke
				(width 0.1)
				(type default)
			)
			(layer "B.Fab")
		)
		(fp_line
			(start 0.67945 0.3048)
			(end 0.67945 -0.305054)
			(stroke
				(width 0.1)
				(type default)
			)
			(layer "B.Fab")
		)
		(fp_line
			(start -0.120396 0.2794)
			(end 0.12065 0.2794)
			(stroke
				(width 0.1)
				(type default)
			)
			(layer "B.Fab")
		)
		(fp_line
			(start 0.12065 0.2794)
			(end 0.12065 0.3048)
			(stroke
				(width 0.1)
				(type default)
			)
			(layer "B.Fab")
		)
		(fp_line
			(start -0.12065 -0.2794)
			(end -0.12065 -0.3048)
			(stroke
				(width 0.1)
				(type default)
			)
			(layer "B.Fab")
		)
		(fp_line
			(start 0.12065 -0.2794)
			(end -0.12065 -0.2794)
			(stroke
				(width 0.1)
				(type default)
			)
			(layer "B.Fab")
		)
		(fp_line
			(start -0.67945 -0.3048)
			(end -0.67945 0.3048)
			(stroke
				(width 0.1)
				(type default)
			)
			(layer "B.Fab")
		)
		(fp_line
			(start -0.12065 -0.3048)
			(end -0.67945 -0.3048)
			(stroke
				(width 0.1)
				(type default)
			)
			(layer "B.Fab")
		)
		(fp_line
			(start 0.12065 -0.305054)
			(end 0.12065 -0.2794)
			(stroke
				(width 0.1)
				(type default)
			)
			(layer "B.Fab")
		)
		(fp_line
			(start 0.67945 -0.305054)
			(end 0.12065 -0.305054)
			(stroke
				(width 0.1)
				(type default)
			)
			(layer "B.Fab")
		)
		(pad "1" smd circle
			(at 0.40005 0 90)
			(size 0 0)
			(layers "B.Cu" "B.Mask" "B.Paste")
			(net "P3V3_PEX_USB_HUB")
		)
		(pad "2" smd circle
			(at -0.40005 0 90)
			(size 0 0)
			(layers "B.Cu" "B.Mask" "B.Paste")
			(net "GND")
		)
	)
	(footprint ""
		(layer "B.Cu")
		(at 392.749786 -295.89984)
		(property "Reference" "C3527"
			(at 0 0 0)
			(layer "B.SilkS")
			(hide yes)
			(effects
				(font
					(size 1.27 1.27)
				)
				(justify mirror)
			)
		)
		(property "Value" ""
			(at 0 0 0)
			(layer "B.Fab")
			(effects
				(font
					(size 1.27 1.27)
				)
				(justify mirror)
			)
		)
		(duplicate_pad_numbers_are_jumpers no)
		(fp_line
			(start -0.299974 -0.150114)
			(end -0.299974 0.150114)
			(stroke
				(width 0.1)
				(type default)
			)
			(layer "B.Fab")
		)
		(fp_line
			(start -0.299974 0.150114)
			(end 0.299974 0.150114)
			(stroke
				(width 0.1)
				(type default)
			)
			(layer "B.Fab")
		)
		(fp_line
			(start 0.299974 -0.150114)
			(end -0.299974 -0.150114)
			(stroke
				(width 0.1)
				(type default)
			)
			(layer "B.Fab")
		)
		(fp_line
			(start 0.299974 0.150114)
			(end 0.299974 -0.150114)
			(stroke
				(width 0.1)
				(type default)
			)
			(layer "B.Fab")
		)
		(pad "1" smd rect
			(at 0.2667 0 180)
			(size 0.3048 0.381)
			(layers "B.Cu" "B.Mask" "B.Paste")
			(net "P1V8_PEX")
		)
		(pad "2" smd rect
			(at -0.2667 0 180)
			(size 0.3048 0.381)
			(layers "B.Cu" "B.Mask" "B.Paste")
			(net "GND")
		)
	)
	(footprint ""
		(layer "B.Cu")
		(at 111.276892 -333.855314)
		(property "Reference" "R1214"
			(at 0 0 0)
			(layer "B.SilkS")
			(hide yes)
			(effects
				(font
					(size 1.27 1.27)
				)
				(justify mirror)
			)
		)
		(property "Value" ""
			(at 0 0 0)
			(layer "B.Fab")
			(effects
				(font
					(size 1.27 1.27)
				)
				(justify mirror)
			)
		)
		(duplicate_pad_numbers_are_jumpers no)
		(fp_line
			(start -1.2954 -0.5842)
			(end -1.2954 0.5842)
			(stroke
				(width 0.1524)
				(type default)
			)
			(layer "B.SilkS")
		)
		(fp_line
			(start -1.2954 0.5842)
			(end 1.2954 0.5842)
			(stroke
				(width 0.1524)
				(type default)
			)
			(layer "B.SilkS")
		)
		(fp_line
			(start 1.2954 -0.5842)
			(end -1.2954 -0.5842)
			(stroke
				(width 0.1524)
				(type default)
			)
			(layer "B.SilkS")
		)
		(fp_line
			(start 1.2954 0.5842)
			(end 1.2954 -0.5842)
			(stroke
				(width 0.1524)
				(type default)
			)
			(layer "B.SilkS")
		)
		(fp_line
			(start -1.1938 -0.406654)
			(end -1.1938 0.4064)
			(stroke
				(width 0.1)
				(type default)
			)
			(layer "B.Fab")
		)
		(fp_line
			(start -1.1938 0.4064)
			(end -0.8636 0.4064)
			(stroke
				(width 0.1)
				(type default)
			)
			(layer "B.Fab")
		)
		(fp_line
			(start -0.8636 -0.4572)
			(end -0.8636 -0.406654)
			(stroke
				(width 0.1)
				(type default)
			)
			(layer "B.Fab")
		)
		(fp_line
			(start -0.8636 -0.406654)
			(end -1.1938 -0.406654)
			(stroke
				(width 0.1)
				(type default)
			)
			(layer "B.Fab")
		)
		(fp_line
			(start -0.8636 0.4064)
			(end -0.8636 0.4572)
			(stroke
				(width 0.1)
				(type default)
			)
			(layer "B.Fab")
		)
		(fp_line
			(start -0.8636 0.4572)
			(end 0.8636 0.4572)
			(stroke
				(width 0.1)
				(type default)
			)
			(layer "B.Fab")
		)
		(fp_line
			(start 0.8636 -0.4572)
			(end -0.8636 -0.4572)
			(stroke
				(width 0.1)
				(type default)
			)
			(layer "B.Fab")
		)
		(fp_line
			(start 0.8636 -0.406654)
			(end 0.8636 -0.4572)
			(stroke
				(width 0.1)
				(type default)
			)
			(layer "B.Fab")
		)
		(fp_line
			(start 0.8636 0.4064)
			(end 1.1938 0.4064)
			(stroke
				(width 0.1)
				(type default)
			)
			(layer "B.Fab")
		)
		(fp_line
			(start 0.8636 0.4318)
			(end 0.8636 0.4064)
			(stroke
				(width 0.1)
				(type default)
			)
			(layer "B.Fab")
		)
		(fp_line
			(start 0.8636 0.4572)
			(end 0.8636 0.4318)
			(stroke
				(width 0.1)
				(type default)
			)
			(layer "B.Fab")
		)
		(fp_line
			(start 1.1938 -0.406654)
			(end 0.8636 -0.406654)
			(stroke
				(width 0.1)
				(type default)
			)
			(layer "B.Fab")
		)
		(fp_line
			(start 1.1938 0.4064)
			(end 1.1938 -0.406654)
			(stroke
				(width 0.1)
				(type default)
			)
			(layer "B.Fab")
		)
		(pad "1" smd rect
			(at 0.7366 0 270)
			(size 0.7112 0.8128)
			(layers "B.Cu" "B.Mask" "B.Paste")
			(net "P3V3_CLK_BUFFER_9ZXL0451E_VZX3P3")
		)
		(pad "2" smd rect
			(at -0.7366 0 270)
			(size 0.7112 0.8128)
			(layers "B.Cu" "B.Mask" "B.Paste")
			(net "P3V3_CLK_BUFFER_9ZXL0451E_VZX3P3A")
		)
	)
	(footprint ""
		(layer "B.Cu")
		(at 134.144766 -308.668674 90)
		(property "Reference" "C4251"
			(at 0 0 90)
			(layer "B.SilkS")
			(hide yes)
			(effects
				(font
					(size 1.27 1.27)
				)
				(justify mirror)
			)
		)
		(property "Value" ""
			(at 0 0 90)
			(layer "B.Fab")
			(effects
				(font
					(size 1.27 1.27)
				)
				(justify mirror)
			)
		)
		(duplicate_pad_numbers_are_jumpers no)
		(fp_line
			(start 0.299974 -0.150114)
			(end -0.299974 -0.150114)
			(stroke
				(width 0.1)
				(type default)
			)
			(layer "B.Fab")
		)
		(fp_line
			(start -0.299974 -0.150114)
			(end -0.299974 0.150114)
			(stroke
				(width 0.1)
				(type default)
			)
			(layer "B.Fab")
		)
		(fp_line
			(start 0.299974 0.150114)
			(end 0.299974 -0.150114)
			(stroke
				(width 0.1)
				(type default)
			)
			(layer "B.Fab")
		)
		(fp_line
			(start -0.299974 0.150114)
			(end 0.299974 0.150114)
			(stroke
				(width 0.1)
				(type default)
			)
			(layer "B.Fab")
		)
		(pad "1" smd rect
			(at 0.2667 0 270)
			(size 0.3048 0.381)
			(layers "B.Cu" "B.Mask" "B.Paste")
			(net "P0V8_PEX1")
		)
		(pad "2" smd rect
			(at -0.2667 0 270)
			(size 0.3048 0.381)
			(layers "B.Cu" "B.Mask" "B.Paste")
			(net "GND")
		)
	)
)
